# BASEBOARD_FAB2 (Tioga Pass) — schematic netlist excerpt (pin names and nets, part order shuffled) for the footprints in the layout excerpt that follows; sources: Cadence DE-HDL packaged netlist, KiCad conversion of Wiwynn_Tioga_Pass_MB.brd

J4E1  SCONN120_H61426002  CONN  pkg SM  page 193
  IOA1  = PVCCMCP_CPU1
  IOA2  = PVCCMCP_CPU1
  IOA3  = PVCCMCP_CPU1
  IOA4  = VSENSE_PVCCMCP_CPU1_SKT_VSEN
  IOA5  = PVCCMCP_CPU1
  IOA6  = PVCCMCP_CPU1
  IOA7  = PVCCMCP_CPU1
  IOA8  = PVCCMCP_CPU1
  IOA9  = PVCCMCP_CPU1
  IOA10  = PVCCMCP_CPU1
  IOA11  = PVCCMCP_CPU1
  IOA12  = PVCCMCP_CPU1
  IOA13  = PVCCMCP_CPU1
  IOA14  = PVCCMCP_CPU1
  IOA15  = PVCCMCP_CPU1
  IOA16  = PVCCMCP_CPU1
  IOA17  = PVCCMCP_CPU1
  IOA18  = PVCCMCP_CPU1
  IOA19  = GND
  IOA20  = GND
  IOB1  = PVCCMCP_CPU1
  IOB2  = PVCCMCP_CPU1
  IOB3  = PVCCMCP_CPU1
  IOB4  = VSENSE_PVCCMCP_CPU1_SKT_VRTN
  IOB5  = PVCCMCP_CPU1
  IOB6  = PVCCMCP_CPU1
  IOB7  = PVCCMCP_CPU1
  IOB8  = PVCCMCP_CPU1
  IOB9  = PVCCMCP_CPU1
  IOB10  = PVCCMCP_CPU1
  IOB11  = PVCCMCP_CPU1
  IOB12  = PVCCMCP_CPU1
  IOB13  = PVCCMCP_CPU1
  IOB14  = PVCCMCP_CPU1
  IOB15  = PVCCMCP_CPU1
  IOB16  = PVCCMCP_CPU1
  IOB17  = PVCCMCP_CPU1
  IOB18  = PVCCMCP_CPU1
  IOB19  = GND
  IOB20  = GND
  IOC1  = PVCCMCP_CPU1
  IOC2  = PVCCMCP_CPU1
  IOC3  = PVCCMCP_CPU1
  IOC4  = PVCCMCP_CPU1
  IOC5  = PVCCMCP_CPU1
  IOC6  = PVCCMCP_CPU1
  IOC7  = PVCCMCP_CPU1
  IOC8  = PVCCMCP_CPU1
  IOC9  = PVCCMCP_CPU1
  IOC10  = PVCCMCP_CPU1
  IOC11  = PVCCMCP_CPU1
  IOC12  = PVCCMCP_CPU1
  IOC13  = PVCCMCP_CPU1
  IOC14  = PVCCMCP_CPU1
  IOC15  = PVCCMCP_CPU1
  IOC16  = PVCCMCP_CPU1
  IOC17  = PVCCMCP_CPU1
  IOC18  = PVCCMCP_CPU1
  IOC19  = GND
  IOC20  = GND
  IOD1  = VSENSE_P1V8MCP_CPU1_SKT_VSEN
  IOD2  = VSENSE_P1V8MCP_CPU1_SKT_VRTN
  IOD3  = P1V8_MCP_CPU1
  IOD4  = GND
  IOD5  = GND
  IOD6  = GND
  IOD7  = GND
  IOD8  = GND
  IOD9  = GND
  IOD10  = GND
  IOD11  = GND
  IOD12  = GND
  IOD13  = GND
  IOD14  = GND
  IOD15  = GND
  IOD16  = GND
  IOD17  = GND
  IOD18  = GND
  IOD19  = GND
  IOD20  = GND
  IOE1  = P1V8_MCP_CPU1
  IOE2  = P1V8_MCP_CPU1
  IOE3  = P1V8_MCP_CPU1
  IOE4  = GND
  IOE5  = CLK_322M_156M_CPU1_OSC_VRM_DP
  IOE6  = GND
  IOE7  = GND
  IOE8  = GND
  IOE9  = GND
  IOE10  = GND
  IOE11  = GND
  IOE12  = GND
  IOE13  = GND
  IOE14  = GND
  IOE15  = GND
  IOE16  = GND
  IOE17  = GND
  IOE18  = GND
  IOE19  = GND
  IOE20  = GND
  IOF1  = P1V8_MCP_CPU1
  IOF2  = P1V8_MCP_CPU1
  IOF3  = P1V8_MCP_CPU1
  IOF4  = GND
  IOF5  = CLK_322M_156M_CPU1_OSC_VRM_DN
  IOF6  = GND
  IOF7  = GND
  IOF8  = GND
  IOF9  = GND
  IOF10  = GND
  IOF11  = GND
  IOF12  = GND
  IOF13  = GND
  IOF14  = GND
  IOF15  = GND
  IOF16  = GND
  IOF17  = GND
  IOF18  = GND
  IOF19  = GND
  IOF20  = GND

(kicad_pcb
	(version 20260206)
	(generator "pcbnew")
	(generator_version "10.0")
	(general
		(thickness 1.6)
		(legacy_teardrops no)
	)
	(paper "A4")
	(title_block
		(title "Wiwynn_Tioga_Pass_MB.brd")
		(comment 1 "Tioga Pass / footprint 1695 of 4770 (J4E1), pads 102-122 of 122")
	)
	(layers
		(0 "F.Cu" signal "TOP")
		(4 "In1.Cu" signal "L2GND")
		(6 "In2.Cu" signal "L3")
		(8 "In3.Cu" signal "L4GND")
		(10 "In4.Cu" signal "L5")
		(12 "In5.Cu" signal "L6GND")
		(14 "In6.Cu" signal "L7VCC")
		(16 "In7.Cu" signal "L8VCC")
		(18 "In8.Cu" signal "L9GND")
		(20 "In9.Cu" signal "L10")
		(22 "In10.Cu" signal "L11GND")
		(24 "In11.Cu" signal "L12")
		(26 "In12.Cu" signal "L13GND")
		(2 "B.Cu" signal "BOTTOM")
		(9 "F.Adhes" user "F.Adhesive")
		(11 "B.Adhes" user "B.Adhesive")
		(13 "F.Paste" user "Package Geometry/Pastemask Top")
		(15 "B.Paste" user "Package Geometry/Pastemask Bottom")
		(5 "F.SilkS" user "Ref Des/Silkscreen Top")
		(7 "B.SilkS" user "Ref Des/Silkscreen Bottom")
		(1 "F.Mask" user "Board Geometry/Soldermask Top")
		(3 "B.Mask" user "Board Geometry/Soldermask Bottom")
		(17 "Dwgs.User" user "User.Drawings")
		(19 "Cmts.User" user "User.Comments")
		(21 "Eco1.User" user "User.Eco1")
		(23 "Eco2.User" user "User.Eco2")
		(25 "Edge.Cuts" user "Board Geometry/Outline")
		(27 "Margin" user)
		(31 "F.CrtYd" user "Package Geometry/Place Bound Top")
		(29 "B.CrtYd" user "Package Geometry/Place Bound Bottom")
		(35 "F.Fab" user "Ref Des/Assembly Top")
		(33 "B.Fab" user "Ref Des/Assembly Bottom")
	)
	(footprint ""
		(layer "F.Cu")
		(at 164.615114 -43.80103 90)
		(property "Reference" "J4E1"
			(at -3.59283 -5.018024 90)
			(unlocked yes)
			(layer "F.SilkS")
			(effects
				(font
					(size 0.7874 0.5842)
					(thickness 0.1524)
				)
			)
		)
		(property "Value" ""
			(at 0 0 90)
			(layer "F.Fab")
			(effects
				(font
					(size 1.27 1.27)
				)
			)
		)
		(duplicate_pad_numbers_are_jumpers no)
		(pad "E20" smd circle
			(at -5.08 24.13 90)
			(size 0.635 0.635)
			(layers "F.Cu" "F.Mask" "F.Paste")
			(net "GND")
		)
		(pad "F1" smd circle
			(at -6.35 0 90)
			(size 0.635 0.635)
			(layers "F.Cu" "F.Mask" "F.Paste")
			(net "P1V8_MCP_CPU1")
		)
		(pad "F2" smd circle
			(at -6.35 1.27 90)
			(size 0.635 0.635)
			(layers "F.Cu" "F.Mask" "F.Paste")
			(net "P1V8_MCP_CPU1")
		)
		(pad "F3" smd circle
			(at -6.35 2.54 90)
			(size 0.635 0.635)
			(layers "F.Cu" "F.Mask" "F.Paste")
			(net "P1V8_MCP_CPU1")
		)
		(pad "F4" smd circle
			(at -6.35 3.81 90)
			(size 0.635 0.635)
			(layers "F.Cu" "F.Mask" "F.Paste")
			(net "GND")
		)
		(pad "F5" smd circle
			(at -6.35 5.08 90)
			(size 0.635 0.635)
			(layers "F.Cu" "F.Mask" "F.Paste")
			(net "CLK_322M_156M_CPU1_OSC_VRM_DN")
		)
		(pad "F6" smd circle
			(at -6.35 6.35 90)
			(size 0.635 0.635)
			(layers "F.Cu" "F.Mask" "F.Paste")
			(net "GND")
		)
		(pad "F7" smd circle
			(at -6.35 7.62 90)
			(size 0.635 0.635)
			(layers "F.Cu" "F.Mask" "F.Paste")
			(net "GND")
		)
		(pad "F8" smd circle
			(at -6.35 8.89 90)
			(size 0.635 0.635)
			(layers "F.Cu" "F.Mask" "F.Paste")
			(net "GND")
		)
		(pad "F9" smd circle
			(at -6.35 10.16 90)
			(size 0.635 0.635)
			(layers "F.Cu" "F.Mask" "F.Paste")
			(net "GND")
		)
		(pad "F10" smd circle
			(at -6.35 11.43 90)
			(size 0.635 0.635)
			(layers "F.Cu" "F.Mask" "F.Paste")
			(net "GND")
		)
		(pad "F11" smd circle
			(at -6.35 12.7 90)
			(size 0.635 0.635)
			(layers "F.Cu" "F.Mask" "F.Paste")
			(net "GND")
		)
		(pad "F12" smd circle
			(at -6.35 13.97 90)
			(size 0.635 0.635)
			(layers "F.Cu" "F.Mask" "F.Paste")
			(net "GND")
		)
		(pad "F13" smd circle
			(at -6.35 15.24 90)
			(size 0.635 0.635)
			(layers "F.Cu" "F.Mask" "F.Paste")
			(net "GND")
		)
		(pad "F14" smd circle
			(at -6.35 16.51 90)
			(size 0.635 0.635)
			(layers "F.Cu" "F.Mask" "F.Paste")
			(net "GND")
		)
		(pad "F15" smd circle
			(at -6.35 17.78 90)
			(size 0.635 0.635)
			(layers "F.Cu" "F.Mask" "F.Paste")
			(net "GND")
		)
		(pad "F16" smd circle
			(at -6.35 19.05 90)
			(size 0.635 0.635)
			(layers "F.Cu" "F.Mask" "F.Paste")
			(net "GND")
		)
		(pad "F17" smd circle
			(at -6.35 20.32 90)
			(size 0.635 0.635)
			(layers "F.Cu" "F.Mask" "F.Paste")
			(net "GND")
		)
		(pad "F18" smd circle
			(at -6.35 21.59 90)
			(size 0.635 0.635)
			(layers "F.Cu" "F.Mask" "F.Paste")
			(net "GND")
		)
		(pad "F19" smd circle
			(at -6.35 22.86 90)
			(size 0.635 0.635)
			(layers "F.Cu" "F.Mask" "F.Paste")
			(net "GND")
		)
		(pad "F20" smd circle
			(at -6.35 24.13 90)
			(size 0.635 0.635)
			(layers "F.Cu" "F.Mask" "F.Paste")
			(net "GND")
		)
	)
)
